G04 ================== begin FILE IDENTIFICATION RECORD ==================*
G04 Layout Name:  9051_F0T_Panel_BD_Front_D_v02_20221209_1310.brd*
G04 Film Name:    pmt*
G04 File Format:  Gerber RS274X*
G04 File Origin:  Cadence Allegro 17.2-S081*
G04 Origin Date:  Mon Dec 12 15:51:17 2022*
G04 *
G04 Layer:  DRAWING FORMAT/TITLE_BLOCK_A*
G04 Layer:  VIA CLASS/PASTEMASK_TOP*
G04 Layer:  PIN/PASTEMASK_TOP*
G04 Layer:  PACKAGE GEOMETRY/PASTEMASK_TOP*
G04 Layer:  MANUFACTURING/PHOTOPLOT_OUTLINE*
G04 Layer:  DRAWING FORMAT/TITLE_BLOCK*
G04 Layer:  DRAWING FORMAT/TITLE_DATA_PMT*
G04 *
G04 Offset:    (0.00 0.00)*
G04 Mirror:    No*
G04 Mode:      Positive*
G04 Rotation:  0*
G04 FullContactRelief:  No*
G04 UndefLineWidth:     6.00*
G04 ================== end FILE IDENTIFICATION RECORD ====================*
%FSLAX25Y25*MOIN*%
%IR0*IPPOS*OFA0.00000B0.00000*MIA0B0*SFA1.00000B1.00000*%
%ADD36O,.052X.103*%
%ADD16C,.03*%
%ADD35C,.042*%
%ADD37C,.044*%
%ADD23C,.054*%
%ADD17C,.048*%
%ADD11C,.039*%
%ADD39R,.044X.044*%
%ADD26R,.054X.054*%
%ADD10R,.048X.048*%
%AMMACRO33*
4,1,28,-.00748,-.00052,
-.00984,-.00052,
-.00984,-.00603,
-.009782,-.006705,
-.009607,-.007359,
-.009321,-.007974,
-.008933,-.008529,
-.008455,-.009009,
-.0079,-.009398,
-.007286,-.009685,
-.006632,-.009861,
-.005957,-.00992,
-.00591,-.00992,
.00591,-.00992,
.006585,-.009869,
.007242,-.009701,
.007859,-.009421,
.008418,-.009039,
.008903,-.008565,
.009297,-.008015,
.009591,-.007404,
.009773,-.006751,
.00984,-.006077,
.00984,-.00603,
.00984,-.00052,
.00748,-.00052,
.00748,.00991,
-.00748,.00991,
-.00748,-.00052,
0.0*
%
%ADD33MACRO33*%
%AMMACRO13*
4,1,28,-.00052,.00748,
-.00052,.00984,
-.00603,.00984,
-.006705,.009782,
-.007359,.009607,
-.007974,.009321,
-.008529,.008933,
-.009009,.008455,
-.009398,.0079,
-.009685,.007286,
-.009861,.006632,
-.00992,.005957,
-.00992,.00591,
-.00992,-.00591,
-.009869,-.006585,
-.009701,-.007242,
-.009421,-.007859,
-.009039,-.008418,
-.008565,-.008903,
-.008015,-.009297,
-.007404,-.009591,
-.006751,-.009773,
-.006077,-.00984,
-.00603,-.00984,
-.00052,-.00984,
-.00052,-.00748,
.00991,-.00748,
.00991,.00748,
-.00052,.00748,
0.0*
%
%ADD13MACRO13*%
%AMMACRO32*
4,1,28,-.00748,.00051,
-.00984,.00051,
-.00984,.00602,
-.009782,.006695,
-.009607,.007349,
-.009321,.007964,
-.008933,.008519,
-.008455,.008998,
-.0079,.009388,
-.007287,.009675,
-.006632,.009851,
-.005958,.00991,
-.00591,.00991,
.00591,.00991,
.006585,.009859,
.007242,.009691,
.007859,.009411,
.008418,.009029,
.008903,.008555,
.009297,.008005,
.00959,.007394,
.009773,.006742,
.00984,.006068,
.00984,.00602,
.00984,.00051,
.00748,.00051,
.00748,-.00992,
-.00748,-.00992,
-.00748,.00051,
0.0*
%
%ADD32MACRO32*%
%AMMACRO12*
4,1,28,.00051,.00748,
.00051,.00984,
.00602,.00984,
.006695,.009782,
.007349,.009607,
.007964,.009321,
.008519,.008933,
.008998,.008455,
.009388,.0079,
.009675,.007287,
.009851,.006632,
.00991,.005958,
.00991,.00591,
.00991,-.00591,
.009859,-.006585,
.009691,-.007242,
.009411,-.007859,
.009029,-.008418,
.008555,-.008903,
.008005,-.009297,
.007394,-.00959,
.006742,-.009773,
.006068,-.00984,
.00602,-.00984,
.00051,-.00984,
.00051,-.00748,
-.00992,-.00748,
-.00992,.00748,
.00051,.00748,
0.0*
%
%ADD12MACRO12*%
%ADD41R,.024X.02*%
%ADD28R,.02X.024*%
%ADD46R,.04X.05*%
%ADD45R,.02X.018*%
%ADD18R,.032X.024*%
%ADD42R,.052X.024*%
%ADD44R,.014X.036*%
%ADD34R,.015X.053*%
%ADD31R,.036X.024*%
%ADD25R,.017X.024*%
%ADD24R,.056X.04*%
%ADD21R,.054X.024*%
%ADD19R,.032X.028*%
%ADD40R,.024X.036*%
%ADD22R,.054X.016*%
%ADD43R,.038X.024*%
%ADD38O,.052X.075*%
%ADD27R,.054X.044*%
%ADD20R,.056X.024*%
%AMMACRO30*
4,1,28,.00748,.00052,
.00984,.00052,
.00984,.00603,
.009782,.006705,
.009607,.007359,
.009321,.007974,
.008933,.008529,
.008455,.009009,
.0079,.009398,
.007286,.009685,
.006632,.009861,
.005957,.00992,
.00591,.00992,
-.00591,.00992,
-.006585,.009869,
-.007242,.009701,
-.007859,.009421,
-.008418,.009039,
-.008903,.008565,
-.009297,.008015,
-.009591,.007404,
-.009773,.006751,
-.00984,.006077,
-.00984,.00603,
-.00984,.00052,
-.00748,.00052,
-.00748,-.00991,
.00748,-.00991,
.00748,.00052,
0.0*
%
%ADD30MACRO30*%
%AMMACRO15*
4,1,28,.00052,-.00748,
.00052,-.00984,
.00603,-.00984,
.006705,-.009782,
.007359,-.009607,
.007974,-.009321,
.008529,-.008933,
.009009,-.008455,
.009398,-.0079,
.009685,-.007286,
.009861,-.006632,
.00992,-.005957,
.00992,-.00591,
.00992,.00591,
.009869,.006585,
.009701,.007242,
.009421,.007859,
.009039,.008418,
.008565,.008903,
.008015,.009297,
.007404,.009591,
.006751,.009773,
.006077,.00984,
.00603,.00984,
.00052,.00984,
.00052,.00748,
-.00991,.00748,
-.00991,-.00748,
.00052,-.00748,
0.0*
%
%ADD15MACRO15*%
%AMMACRO29*
4,1,28,.00748,-.00051,
.00984,-.00051,
.00984,-.00602,
.009782,-.006695,
.009607,-.007349,
.009321,-.007964,
.008933,-.008519,
.008455,-.008998,
.0079,-.009388,
.007287,-.009675,
.006632,-.009851,
.005958,-.00991,
.00591,-.00991,
-.00591,-.00991,
-.006585,-.009859,
-.007242,-.009691,
-.007859,-.009411,
-.008418,-.009029,
-.008903,-.008555,
-.009297,-.008005,
-.00959,-.007394,
-.009773,-.006742,
-.00984,-.006068,
-.00984,-.00602,
-.00984,-.00051,
-.00748,-.00051,
-.00748,.00992,
.00748,.00992,
.00748,-.00051,
0.0*
%
%ADD29MACRO29*%
%AMMACRO14*
4,1,28,-.00051,-.00748,
-.00051,-.00984,
-.00602,-.00984,
-.006695,-.009782,
-.007349,-.009607,
-.007964,-.009321,
-.008519,-.008933,
-.008998,-.008455,
-.009388,-.0079,
-.009675,-.007287,
-.009851,-.006632,
-.00991,-.005958,
-.00991,-.00591,
-.00991,.00591,
-.009859,.006585,
-.009691,.007242,
-.009411,.007859,
-.009029,.008418,
-.008555,.008903,
-.008005,.009297,
-.007394,.00959,
-.006742,.009773,
-.006068,.00984,
-.00602,.00984,
-.00051,.00984,
-.00051,.00748,
.00992,.00748,
.00992,-.00748,
-.00051,-.00748,
0.0*
%
%ADD14MACRO14*%
%ADD47C,.006*%
G75*
%LPD*%
G75*
G54D10*
X10315Y20079D03*
X33937D03*
G54D20*
X28567Y186000D03*
Y191000D03*
Y196000D03*
Y201000D03*
X49433Y196000D03*
Y191000D03*
Y186000D03*
Y201000D03*
G54D11*
X11489Y85883D03*
X51000Y301000D03*
X105000Y234500D03*
G54D30*
X59500Y60483D03*
X65000Y78983D03*
X59500Y100483D03*
X81500Y250983D03*
X85500D03*
G54D21*
X36484Y213532D03*
Y242468D03*
X59516Y213532D03*
Y242468D03*
G54D12*
X13484Y114500D03*
Y103500D03*
X16984Y196000D03*
Y188000D03*
Y200000D03*
Y204000D03*
X24984Y217500D03*
Y209500D03*
Y225500D03*
X54484Y83500D03*
X69984Y67500D03*
X78484Y91000D03*
Y87000D03*
X70484Y91000D03*
X78484Y95000D03*
Y99000D03*
X70484Y95000D03*
X63984Y197500D03*
X73984Y219500D03*
X58984Y201500D03*
X73984Y227500D03*
Y231500D03*
Y223500D03*
X68984Y244500D03*
X73484Y265500D03*
X93984Y120000D03*
X117984Y126000D03*
Y130000D03*
X145984Y88000D03*
Y80000D03*
Y104000D03*
Y96000D03*
G54D22*
X36484Y216484D03*
Y219043D03*
Y221602D03*
Y224161D03*
Y226720D03*
Y229280D03*
Y231839D03*
Y234398D03*
Y236957D03*
Y239516D03*
X59516Y221602D03*
Y219043D03*
Y216484D03*
Y239516D03*
Y236957D03*
Y234398D03*
Y231839D03*
Y229280D03*
Y226720D03*
Y224161D03*
G54D40*
X98437Y107547D03*
X128385Y76431D03*
G54D31*
X77453Y80437D03*
G54D13*
X10517Y114500D03*
Y103500D03*
X14017Y196000D03*
Y188000D03*
Y200000D03*
Y204000D03*
X22017Y217500D03*
Y209500D03*
Y225500D03*
X51517Y83500D03*
X56017Y201500D03*
X67017Y67500D03*
X75517Y91000D03*
Y87000D03*
X67517Y91000D03*
X75517Y95000D03*
Y99000D03*
X67517Y95000D03*
X61017Y197500D03*
X71017Y219500D03*
Y227500D03*
Y231500D03*
Y223500D03*
X66017Y244500D03*
X70517Y265500D03*
X91017Y120000D03*
X115017Y126000D03*
Y130000D03*
X143017Y88000D03*
Y80000D03*
Y104000D03*
Y96000D03*
G54D14*
X10516Y99500D03*
Y110500D03*
X14016Y192000D03*
Y184000D03*
X36016Y103500D03*
Y114500D03*
X22016Y221500D03*
Y213500D03*
Y229500D03*
Y241500D03*
Y233500D03*
Y237500D03*
Y245500D03*
X51516Y87500D03*
Y110000D03*
X42516Y247000D03*
X67516Y87000D03*
Y99000D03*
X61016Y177500D03*
Y181500D03*
Y185500D03*
Y193500D03*
Y189500D03*
X71016Y239500D03*
Y235500D03*
X60016Y265500D03*
X120854Y27211D03*
X143016Y92000D03*
Y84000D03*
Y76000D03*
Y108000D03*
Y100000D03*
G54D41*
X90563Y106760D03*
Y114240D03*
X98437D03*
X120511Y75644D03*
Y83124D03*
X128385D03*
G54D32*
X77500Y250984D03*
G54D23*
X57480Y26299D03*
X67480D03*
G54D15*
X13483Y99500D03*
Y110500D03*
X16983Y192000D03*
Y184000D03*
X24983Y221500D03*
Y213500D03*
Y229500D03*
Y241500D03*
Y233500D03*
Y237500D03*
Y245500D03*
X54483Y87500D03*
Y110000D03*
X38983Y103500D03*
Y114500D03*
X45483Y247000D03*
X70483Y87000D03*
Y99000D03*
X63983Y177500D03*
Y181500D03*
Y185500D03*
Y193500D03*
Y189500D03*
X73983Y239500D03*
Y235500D03*
X62983Y265500D03*
X123821Y27211D03*
X145983Y92000D03*
Y84000D03*
Y76000D03*
Y108000D03*
Y100000D03*
G54D24*
X59586Y43608D03*
Y51088D03*
X68248Y47348D03*
X68720Y57967D03*
X77382Y61707D03*
Y54227D03*
G54D42*
X122983Y6716D03*
Y11716D03*
Y16716D03*
Y21716D03*
X143849Y6716D03*
Y21716D03*
Y16716D03*
Y11716D03*
G54D33*
X77500Y248017D03*
G54D43*
X121571Y112760D03*
Y116500D03*
Y120240D03*
X130429Y112760D03*
Y120240D03*
Y116500D03*
G54D25*
X54059Y92260D03*
X51500D03*
X48941D03*
Y99740D03*
X51500D03*
X54059D03*
G54D34*
X64764Y274803D03*
X67126D03*
X69489D03*
X71851D03*
X74213D03*
X76575D03*
X78937D03*
X64764Y284055D03*
X67126D03*
X69489D03*
X71851D03*
X74213D03*
X76575D03*
X78937D03*
X81300Y274803D03*
X83662D03*
X86024D03*
X88386D03*
X90748D03*
X93111D03*
X95473D03*
X97835D03*
X100197D03*
X81300Y284055D03*
X83662D03*
X86024D03*
X88386D03*
X90748D03*
X93111D03*
X95473D03*
X97835D03*
X100197D03*
X102559Y274803D03*
X104922D03*
X107284D03*
X102559Y284055D03*
X104922D03*
X107284D03*
G54D16*
X16000Y119500D03*
X31000Y112000D03*
Y101000D03*
X22000Y190000D03*
Y201000D03*
Y196000D03*
X30000Y223500D03*
Y218500D03*
Y213500D03*
Y236500D03*
Y241500D03*
X42400Y93000D03*
X51500Y105000D03*
X44500Y104000D03*
X56000Y186000D03*
Y196500D03*
Y191500D03*
X50500Y249000D03*
X79000Y223500D03*
X66000Y224500D03*
X81500Y243001D03*
X81000Y235500D03*
X66000Y229500D03*
Y239500D03*
Y234500D03*
X61256Y254000D03*
X72500Y250000D03*
X89000Y128000D03*
X82500Y262000D03*
X88500D03*
X83568Y256068D03*
X137500Y100000D03*
X133000Y104000D03*
X137500Y107000D03*
G54D44*
X126121Y90575D03*
X122775D03*
X126121Y97267D03*
X122775D03*
G54D26*
X77480Y26299D03*
G54D17*
X20315Y20079D03*
X43937D03*
G54D35*
X61516Y326772D03*
Y314961D03*
X110532Y326772D03*
Y314961D03*
G54D27*
X76755Y39441D03*
Y46921D03*
G54D18*
X25650Y101000D03*
X19350Y98441D03*
Y103559D03*
X25650Y112000D03*
X19350Y109441D03*
Y114559D03*
G54D45*
X126121Y92117D03*
X122775D03*
X126121Y95267D03*
X122775D03*
G54D36*
X87756Y47244D03*
X109095Y89370D03*
G54D19*
X36600Y98500D03*
Y109500D03*
X42400Y98500D03*
Y109500D03*
X63600Y37100D03*
X69400D03*
X70600Y261000D03*
X76400D03*
X65400D03*
X59600D03*
G54D46*
X145000Y113500D03*
X138000D03*
X145000Y127500D03*
X138000D03*
X145000Y120500D03*
X138000D03*
X124000Y134500D03*
X131000D03*
X124000Y127500D03*
X131000D03*
X145000Y134500D03*
X138000D03*
G54D28*
X78240Y72563D03*
X70760D03*
Y80437D03*
G54D37*
X101969Y52480D03*
Y68228D03*
Y60354D03*
X94882Y54449D03*
Y64291D03*
Y72165D03*
X101969Y83976D03*
Y76102D03*
G54D47*
G01X-117168Y-317735D02*
Y-322735D01*
G01X-118625Y-317735D02*
X-115711D01*
G01X-110801Y-322735D02*
X-113335D01*
Y-317735D01*
X-110801D01*
G01X-111815Y-320152D02*
X-113335D01*
G01X-108235Y-317735D02*
Y-322735D01*
X-105701D01*
G01X-101868Y-322902D02*
X-101995Y-322818D01*
Y-322652D01*
X-101868Y-322568D01*
X-101741Y-322652D01*
Y-322818D01*
X-101868Y-322902D01*
G01Y-320652D02*
X-101995Y-320568D01*
Y-320402D01*
X-101868Y-320318D01*
X-101741Y-320402D01*
Y-320568D01*
X-101868Y-320652D01*
G01X-97085Y-324402D02*
X-97718Y-323568D01*
X-98035Y-322735D01*
Y-319402D01*
X-97718Y-318568D01*
X-97085Y-317735D01*
G01X-91668D02*
X-92175Y-317902D01*
X-92555Y-318318D01*
X-92808Y-318818D01*
X-92998Y-319485D01*
X-93061Y-320235D01*
X-92998Y-320985D01*
X-92808Y-321652D01*
X-92555Y-322152D01*
X-92175Y-322568D01*
X-91668Y-322735D01*
X-91161Y-322568D01*
X-90781Y-322152D01*
X-90528Y-321652D01*
X-90338Y-320985D01*
X-90275Y-320235D01*
X-90338Y-319485D01*
X-90528Y-318818D01*
X-90781Y-318318D01*
X-91161Y-317902D01*
X-91668Y-317735D01*
G01X-87961Y-321735D02*
X-87581Y-322318D01*
X-87075Y-322652D01*
X-86505Y-322735D01*
X-85998Y-322652D01*
X-85491Y-322235D01*
X-85175Y-321735D01*
X-85111Y-321235D01*
X-85238Y-320652D01*
X-85681Y-320235D01*
X-86125Y-320068D01*
X-86695D01*
G01X-86125D02*
X-85745Y-319818D01*
X-85428Y-319402D01*
X-85301Y-318902D01*
X-85428Y-318402D01*
X-85745Y-317985D01*
X-86315Y-317735D01*
X-86885Y-317818D01*
X-87455Y-318152D01*
G01X-81151Y-324402D02*
X-80518Y-323568D01*
X-80201Y-322735D01*
Y-319402D01*
X-80518Y-318568D01*
X-81151Y-317735D01*
G01X-77761Y-321735D02*
X-77381Y-322318D01*
X-76875Y-322652D01*
X-76305Y-322735D01*
X-75798Y-322652D01*
X-75291Y-322235D01*
X-74975Y-321735D01*
X-74911Y-321235D01*
X-75038Y-320652D01*
X-75481Y-320235D01*
X-75925Y-320068D01*
X-76495D01*
G01X-75925D02*
X-75545Y-319818D01*
X-75228Y-319402D01*
X-75101Y-318902D01*
X-75228Y-318402D01*
X-75545Y-317985D01*
X-76115Y-317735D01*
X-76685Y-317818D01*
X-77255Y-318152D01*
G01X-72471Y-318568D02*
X-72091Y-318068D01*
X-71648Y-317818D01*
X-71141Y-317735D01*
X-70508Y-317902D01*
X-70065Y-318318D01*
X-69938Y-318818D01*
X-70001Y-319318D01*
X-70255Y-319735D01*
X-71521Y-320568D01*
X-72091Y-321152D01*
X-72471Y-321985D01*
X-72598Y-322735D01*
X-69938D01*
G01X-66295D02*
X-66168Y-321652D01*
X-65978Y-320735D01*
X-65725Y-319902D01*
X-65408Y-318985D01*
X-64901Y-317735D01*
X-67435D01*
G01X-61891Y-321068D02*
X-60245D01*
G01X-57171Y-318568D02*
X-56791Y-318068D01*
X-56348Y-317818D01*
X-55841Y-317735D01*
X-55208Y-317902D01*
X-54765Y-318318D01*
X-54638Y-318818D01*
X-54701Y-319318D01*
X-54955Y-319735D01*
X-56221Y-320568D01*
X-56791Y-321152D01*
X-57171Y-321985D01*
X-57298Y-322735D01*
X-54638D01*
G01X-52261Y-321735D02*
X-51881Y-322318D01*
X-51375Y-322652D01*
X-50805Y-322735D01*
X-50298Y-322652D01*
X-49791Y-322235D01*
X-49475Y-321735D01*
X-49411Y-321235D01*
X-49538Y-320652D01*
X-49981Y-320235D01*
X-50425Y-320068D01*
X-50995D01*
G01X-50425D02*
X-50045Y-319818D01*
X-49728Y-319402D01*
X-49601Y-318902D01*
X-49728Y-318402D01*
X-50045Y-317985D01*
X-50615Y-317735D01*
X-51185Y-317818D01*
X-51755Y-318152D01*
G01X-45008Y-322735D02*
Y-317735D01*
X-47351Y-321318D01*
X-44185D01*
G01X-42061Y-321985D02*
X-41681Y-322402D01*
X-41238Y-322652D01*
X-40668Y-322735D01*
X-40098Y-322568D01*
X-39655Y-322235D01*
X-39338Y-321652D01*
X-39275Y-320985D01*
X-39401Y-320318D01*
X-39718Y-319902D01*
X-40161Y-319568D01*
X-40605Y-319485D01*
X-41048Y-319568D01*
X-41618Y-319902D01*
X-41428Y-317735D01*
X-39718D01*
G01X-31671Y-322735D02*
Y-317735D01*
X-29265D01*
G01X-30151Y-320152D02*
X-31671D01*
G01X-26951Y-322735D02*
X-25368Y-317735D01*
X-23785Y-322735D01*
G01X-24355Y-320985D02*
X-26381D01*
G01X-21598Y-322735D02*
X-18938Y-317735D01*
G01X-21598D02*
X-18938Y-322735D01*
G01X-15168Y-322902D02*
X-15295Y-322818D01*
Y-322652D01*
X-15168Y-322568D01*
X-15041Y-322652D01*
Y-322818D01*
X-15168Y-322902D01*
G01Y-320652D02*
X-15295Y-320568D01*
Y-320402D01*
X-15168Y-320318D01*
X-15041Y-320402D01*
Y-320568D01*
X-15168Y-320652D01*
G01X-10385Y-324402D02*
X-11018Y-323568D01*
X-11335Y-322735D01*
Y-319402D01*
X-11018Y-318568D01*
X-10385Y-317735D01*
G01X-4968D02*
X-5475Y-317902D01*
X-5855Y-318318D01*
X-6108Y-318818D01*
X-6298Y-319485D01*
X-6361Y-320235D01*
X-6298Y-320985D01*
X-6108Y-321652D01*
X-5855Y-322152D01*
X-5475Y-322568D01*
X-4968Y-322735D01*
X-4461Y-322568D01*
X-4081Y-322152D01*
X-3828Y-321652D01*
X-3638Y-320985D01*
X-3575Y-320235D01*
X-3638Y-319485D01*
X-3828Y-318818D01*
X-4081Y-318318D01*
X-4461Y-317902D01*
X-4968Y-317735D01*
G01X-1261Y-321735D02*
X-881Y-322318D01*
X-375Y-322652D01*
X195Y-322735D01*
X702Y-322652D01*
X1209Y-322235D01*
X1525Y-321735D01*
X1589Y-321235D01*
X1462Y-320652D01*
X1019Y-320235D01*
X575Y-320068D01*
X5D01*
G01X575D02*
X955Y-319818D01*
X1272Y-319402D01*
X1399Y-318902D01*
X1272Y-318402D01*
X955Y-317985D01*
X385Y-317735D01*
X-185Y-317818D01*
X-755Y-318152D01*
G01X5549Y-324402D02*
X6182Y-323568D01*
X6499Y-322735D01*
Y-319402D01*
X6182Y-318568D01*
X5549Y-317735D01*
G01X8939Y-321735D02*
X9319Y-322318D01*
X9825Y-322652D01*
X10395Y-322735D01*
X10902Y-322652D01*
X11409Y-322235D01*
X11725Y-321735D01*
X11789Y-321235D01*
X11662Y-320652D01*
X11219Y-320235D01*
X10775Y-320068D01*
X10205D01*
G01X10775D02*
X11155Y-319818D01*
X11472Y-319402D01*
X11599Y-318902D01*
X11472Y-318402D01*
X11155Y-317985D01*
X10585Y-317735D01*
X10015Y-317818D01*
X9445Y-318152D01*
G01X14355Y-322152D02*
X14799Y-322568D01*
X15305Y-322735D01*
X15812Y-322568D01*
X16255Y-322068D01*
X16572Y-321318D01*
X16699Y-320568D01*
Y-319652D01*
X16572Y-318902D01*
X16255Y-318235D01*
X15875Y-317902D01*
X15432Y-317735D01*
X14925Y-317902D01*
X14545Y-318235D01*
X14292Y-318735D01*
X14165Y-319402D01*
X14292Y-319985D01*
X14609Y-320568D01*
X14989Y-320902D01*
X15432Y-320985D01*
X15939Y-320818D01*
X16319Y-320402D01*
X16699Y-319652D01*
G01X20405Y-322735D02*
X20532Y-321652D01*
X20722Y-320735D01*
X20975Y-319902D01*
X21292Y-318985D01*
X21799Y-317735D01*
X19265D01*
G01X24809Y-321068D02*
X26455D01*
G01X29339Y-321735D02*
X29719Y-322318D01*
X30225Y-322652D01*
X30795Y-322735D01*
X31302Y-322652D01*
X31809Y-322235D01*
X32125Y-321735D01*
X32189Y-321235D01*
X32062Y-320652D01*
X31619Y-320235D01*
X31175Y-320068D01*
X30605D01*
G01X31175D02*
X31555Y-319818D01*
X31872Y-319402D01*
X31999Y-318902D01*
X31872Y-318402D01*
X31555Y-317985D01*
X30985Y-317735D01*
X30415Y-317818D01*
X29845Y-318152D01*
G01X34629Y-320652D02*
X35072Y-320068D01*
X35452Y-319735D01*
X35959Y-319568D01*
X36402Y-319735D01*
X36719Y-320068D01*
X36972Y-320568D01*
X37035Y-321152D01*
X36972Y-321652D01*
X36719Y-322152D01*
X36339Y-322568D01*
X35895Y-322735D01*
X35389Y-322568D01*
X34945Y-322068D01*
X34692Y-321318D01*
X34629Y-320485D01*
X34755Y-319402D01*
X34945Y-318818D01*
X35262Y-318235D01*
X35705Y-317818D01*
X36149Y-317735D01*
X36592Y-317902D01*
X36909Y-318318D01*
G01X40932Y-322735D02*
Y-317735D01*
X40172Y-318735D01*
G01Y-322735D02*
X41692D01*
G01X46792D02*
Y-317735D01*
X44449Y-321318D01*
X47615D01*
G01X-129168Y-252735D02*
Y-327735D01*
X370832D01*
Y-252735D01*
X-129168D01*
G01X65832D02*
Y-327735D01*
G01Y-302735D02*
X168832D01*
Y-277735D01*
G01X65832D02*
X168832D01*
G01X176339Y-312735D02*
Y-307735D01*
X177605D01*
X178112Y-307985D01*
X178492Y-308318D01*
X178809Y-308818D01*
X179062Y-309402D01*
X179125Y-310235D01*
X179062Y-311068D01*
X178809Y-311652D01*
X178492Y-312152D01*
X178112Y-312485D01*
X177605Y-312735D01*
X176339D01*
G01X181249D02*
X182832Y-307735D01*
X184415Y-312735D01*
G01X183845Y-310985D02*
X181819D01*
G01X187932Y-307735D02*
Y-312735D01*
G01X186475Y-307735D02*
X189389D01*
G01X194299Y-312735D02*
X191765D01*
Y-307735D01*
X194299D01*
G01X193285Y-310152D02*
X191765D01*
G01X198132Y-312902D02*
X198005Y-312818D01*
Y-312652D01*
X198132Y-312568D01*
X198259Y-312652D01*
Y-312818D01*
X198132Y-312902D01*
G01Y-310652D02*
X198005Y-310568D01*
Y-310402D01*
X198132Y-310318D01*
X198259Y-310402D01*
Y-310568D01*
X198132Y-310652D01*
G01X170832Y-252735D02*
Y-327735D01*
G01X168832Y-252735D02*
Y-327735D01*
G01X170832Y-302735D02*
X370832D01*
G01X176465Y-287735D02*
Y-282735D01*
X177985D01*
X178492Y-282985D01*
X178872Y-283568D01*
X178999Y-284235D01*
X178872Y-284902D01*
X178555Y-285402D01*
X177985Y-285652D01*
X176465D01*
G01X181692Y-287902D02*
X183972Y-282735D01*
G01X186475Y-287735D02*
Y-282735D01*
X189389Y-287735D01*
Y-282735D01*
G01X193032Y-287902D02*
X192905Y-287818D01*
Y-287652D01*
X193032Y-287568D01*
X193159Y-287652D01*
Y-287818D01*
X193032Y-287902D01*
G01Y-285652D02*
X192905Y-285568D01*
Y-285402D01*
X193032Y-285318D01*
X193159Y-285402D01*
Y-285568D01*
X193032Y-285652D01*
G01X170832Y-277735D02*
X370832D01*
G01X176465Y-262735D02*
Y-257735D01*
X177985D01*
X178492Y-257985D01*
X178872Y-258568D01*
X178999Y-259235D01*
X178872Y-259902D01*
X178555Y-260402D01*
X177985Y-260652D01*
X176465D01*
G01X181565Y-262735D02*
Y-257735D01*
X183149D01*
X183655Y-257985D01*
X183972Y-258318D01*
X184099Y-258985D01*
X183972Y-259652D01*
X183592Y-260068D01*
X183149Y-260318D01*
X181565D01*
G01X183149D02*
X184099Y-262735D01*
G01X187932D02*
X187425Y-262652D01*
X186982Y-262318D01*
X186602Y-261818D01*
X186349Y-261235D01*
X186222Y-260568D01*
Y-259902D01*
X186349Y-259235D01*
X186602Y-258652D01*
X186982Y-258152D01*
X187425Y-257818D01*
X187932Y-257735D01*
X188439Y-257818D01*
X188882Y-258152D01*
X189262Y-258652D01*
X189515Y-259235D01*
X189642Y-259902D01*
Y-260568D01*
X189515Y-261235D01*
X189262Y-261818D01*
X188882Y-262318D01*
X188439Y-262652D01*
X187932Y-262735D01*
G01X191765Y-261735D02*
X192082Y-262235D01*
X192462Y-262568D01*
X192905Y-262735D01*
X193412Y-262568D01*
X193792Y-262235D01*
X194172Y-261735D01*
X194299Y-261068D01*
Y-257735D01*
G01X199399Y-262735D02*
X196865D01*
Y-257735D01*
X199399D01*
G01X198385Y-260152D02*
X196865D01*
G01X204625Y-258152D02*
X204245Y-257902D01*
X203802Y-257735D01*
X203295D01*
X202725Y-257985D01*
X202282Y-258402D01*
X201965Y-258902D01*
X201712Y-259735D01*
X201649Y-260485D01*
X201775Y-261235D01*
X201965Y-261735D01*
X202345Y-262235D01*
X202789Y-262568D01*
X203232Y-262735D01*
X203675D01*
X204119Y-262568D01*
X204499Y-262318D01*
X204815Y-261985D01*
G01X208332Y-257735D02*
Y-262735D01*
G01X206875Y-257735D02*
X209789D01*
G01X213432Y-262902D02*
X213305Y-262818D01*
Y-262652D01*
X213432Y-262568D01*
X213559Y-262652D01*
Y-262818D01*
X213432Y-262902D01*
G01Y-260652D02*
X213305Y-260568D01*
Y-260402D01*
X213432Y-260318D01*
X213559Y-260402D01*
Y-260568D01*
X213432Y-260652D01*
G01X283832Y-302735D02*
Y-327735D01*
G01X288465Y-305235D02*
Y-310235D01*
X290999D01*
G01X294072Y-305235D02*
X295592D01*
G01X294832D02*
Y-310235D01*
G01X294072D02*
X295592D01*
G01X300439Y-307568D02*
X300692Y-307318D01*
X300882Y-306902D01*
X301009Y-306318D01*
X300882Y-305818D01*
X300629Y-305485D01*
X300185Y-305235D01*
X298475D01*
Y-310235D01*
X300565D01*
X301009Y-309902D01*
X301262Y-309402D01*
X301389Y-308818D01*
X301262Y-308235D01*
X300882Y-307735D01*
X300439Y-307568D01*
X298475D01*
G01X305032Y-310402D02*
X304905Y-310318D01*
Y-310152D01*
X305032Y-310068D01*
X305159Y-310152D01*
Y-310318D01*
X305032Y-310402D01*
G01Y-308152D02*
X304905Y-308068D01*
Y-307902D01*
X305032Y-307818D01*
X305159Y-307902D01*
Y-308068D01*
X305032Y-308152D01*
G01X328832Y-302735D02*
Y-327735D01*
G01X332732Y-305235D02*
Y-310235D01*
G01X331275Y-305235D02*
X334189D01*
G01X337832Y-310235D02*
X337452Y-310152D01*
X337072Y-309818D01*
X336819Y-309235D01*
X336692Y-308568D01*
X336819Y-307902D01*
X337072Y-307318D01*
X337452Y-306985D01*
X337832Y-306902D01*
X338212Y-306985D01*
X338592Y-307318D01*
X338845Y-307902D01*
X338909Y-308568D01*
X338845Y-309235D01*
X338592Y-309818D01*
X338212Y-310152D01*
X337832Y-310235D01*
G01X342932D02*
X342552Y-310152D01*
X342172Y-309818D01*
X341919Y-309235D01*
X341792Y-308568D01*
X341919Y-307902D01*
X342172Y-307318D01*
X342552Y-306985D01*
X342932Y-306902D01*
X343312Y-306985D01*
X343692Y-307318D01*
X343945Y-307902D01*
X344009Y-308568D01*
X343945Y-309235D01*
X343692Y-309818D01*
X343312Y-310152D01*
X342932Y-310235D01*
G01X348032D02*
Y-305235D01*
G01X353132Y-310402D02*
X353005Y-310318D01*
Y-310152D01*
X353132Y-310068D01*
X353259Y-310152D01*
Y-310318D01*
X353132Y-310402D01*
G01Y-308152D02*
X353005Y-308068D01*
Y-307902D01*
X353132Y-307818D01*
X353259Y-307902D01*
Y-308068D01*
X353132Y-308152D01*
G01X328832Y-277735D02*
Y-302735D01*
G01X331465Y-285235D02*
Y-280235D01*
X333049D01*
X333555Y-280485D01*
X333872Y-280818D01*
X333999Y-281485D01*
X333872Y-282152D01*
X333492Y-282568D01*
X333049Y-282818D01*
X331465D01*
G01X333049D02*
X333999Y-285235D01*
G01X339099D02*
X336565D01*
Y-280235D01*
X339099D01*
G01X338085Y-282652D02*
X336565D01*
G01X341349Y-280235D02*
X342932Y-285235D01*
X344515Y-280235D01*
G01X348032Y-285402D02*
X347905Y-285318D01*
Y-285152D01*
X348032Y-285068D01*
X348159Y-285152D01*
Y-285318D01*
X348032Y-285402D01*
G01Y-283152D02*
X347905Y-283068D01*
Y-282902D01*
X348032Y-282818D01*
X348159Y-282902D01*
Y-283068D01*
X348032Y-283152D01*
G01X351592Y-329435D02*
X351672Y-329360D01*
X351732Y-329235D01*
X351772Y-329060D01*
X351732Y-328910D01*
X351652Y-328810D01*
X351512Y-328735D01*
X350972D01*
Y-330235D01*
X351632D01*
X351772Y-330135D01*
X351852Y-329985D01*
X351892Y-329810D01*
X351852Y-329635D01*
X351732Y-329485D01*
X351592Y-329435D01*
X350972D01*
G01X352992Y-330235D02*
Y-329235D01*
G01Y-329410D02*
X352912Y-329310D01*
X352792Y-329260D01*
X352652Y-329235D01*
X352512Y-329285D01*
X352392Y-329385D01*
X352312Y-329535D01*
X352272Y-329735D01*
X352312Y-329935D01*
X352392Y-330085D01*
X352512Y-330185D01*
X352652Y-330235D01*
X352792Y-330210D01*
X352912Y-330135D01*
X352992Y-330035D01*
G01X353532Y-330060D02*
X353632Y-330160D01*
X353772Y-330235D01*
X353892D01*
X354012Y-330185D01*
X354092Y-330110D01*
X354132Y-330010D01*
X354112Y-329860D01*
X354032Y-329785D01*
X353672Y-329635D01*
X353592Y-329460D01*
X353632Y-329335D01*
X353712Y-329260D01*
X353832Y-329235D01*
X353952Y-329260D01*
X354072Y-329335D01*
G01X354732Y-329560D02*
X355372D01*
X355312Y-329385D01*
X355212Y-329285D01*
X355072Y-329235D01*
X354932Y-329260D01*
X354812Y-329335D01*
X354732Y-329510D01*
X354692Y-329660D01*
Y-329810D01*
X354732Y-329960D01*
X354832Y-330110D01*
X354952Y-330210D01*
X355092Y-330235D01*
X355232Y-330185D01*
X355372Y-330035D01*
G01X355872Y-330235D02*
Y-328735D01*
G01Y-329485D02*
X355972Y-329335D01*
X356092Y-329260D01*
X356212Y-329235D01*
X356392Y-329285D01*
X356512Y-329385D01*
X356592Y-329560D01*
Y-329760D01*
X356552Y-329960D01*
X356472Y-330110D01*
X356332Y-330210D01*
X356212Y-330235D01*
X356092Y-330210D01*
X355972Y-330135D01*
X355872Y-330010D01*
G01X357432Y-330235D02*
X357312Y-330210D01*
X357192Y-330110D01*
X357112Y-329935D01*
X357072Y-329735D01*
X357112Y-329535D01*
X357192Y-329360D01*
X357312Y-329260D01*
X357432Y-329235D01*
X357552Y-329260D01*
X357672Y-329360D01*
X357752Y-329535D01*
X357772Y-329735D01*
X357752Y-329935D01*
X357672Y-330110D01*
X357552Y-330210D01*
X357432Y-330235D01*
G01X358992D02*
Y-329235D01*
G01Y-329410D02*
X358912Y-329310D01*
X358792Y-329260D01*
X358652Y-329235D01*
X358512Y-329285D01*
X358392Y-329385D01*
X358312Y-329535D01*
X358272Y-329735D01*
X358312Y-329935D01*
X358392Y-330085D01*
X358512Y-330185D01*
X358652Y-330235D01*
X358792Y-330210D01*
X358912Y-330135D01*
X358992Y-330035D01*
G01X359552Y-330235D02*
Y-329235D01*
G01Y-329435D02*
X359652Y-329335D01*
X359752Y-329260D01*
X359892Y-329235D01*
X359992Y-329260D01*
X360112Y-329335D01*
G01X361392Y-328735D02*
Y-330235D01*
G01Y-330010D02*
X361312Y-330135D01*
X361192Y-330210D01*
X361052Y-330235D01*
X360892Y-330185D01*
X360772Y-330060D01*
X360692Y-329910D01*
X360672Y-329735D01*
X360692Y-329560D01*
X360772Y-329410D01*
X360892Y-329285D01*
X361052Y-329235D01*
X361192Y-329260D01*
X361292Y-329310D01*
X361392Y-329410D01*
G01X363032Y-330235D02*
Y-328735D01*
X363532D01*
X363692Y-328810D01*
X363792Y-328910D01*
X363832Y-329110D01*
X363792Y-329310D01*
X363672Y-329435D01*
X363532Y-329510D01*
X363032D01*
G01X363532D02*
X363832Y-330235D01*
G01X364332Y-329560D02*
X364972D01*
X364912Y-329385D01*
X364812Y-329285D01*
X364672Y-329235D01*
X364532Y-329260D01*
X364412Y-329335D01*
X364332Y-329510D01*
X364292Y-329660D01*
Y-329810D01*
X364332Y-329960D01*
X364432Y-330110D01*
X364552Y-330210D01*
X364692Y-330235D01*
X364832Y-330185D01*
X364972Y-330035D01*
G01X365472Y-329235D02*
X365832Y-330235D01*
X366192Y-329235D01*
G01X367032Y-330285D02*
X366992Y-330260D01*
Y-330210D01*
X367032Y-330185D01*
X367072Y-330210D01*
Y-330260D01*
X367032Y-330285D01*
G01X368192Y-330235D02*
X368232Y-329910D01*
X368292Y-329635D01*
X368372Y-329385D01*
X368472Y-329110D01*
X368632Y-328735D01*
X367832D01*
G01X369592Y-329435D02*
X369672Y-329360D01*
X369732Y-329235D01*
X369772Y-329060D01*
X369732Y-328910D01*
X369652Y-328810D01*
X369512Y-328735D01*
X368972D01*
Y-330235D01*
X369632D01*
X369772Y-330135D01*
X369852Y-329985D01*
X369892Y-329810D01*
X369852Y-329635D01*
X369732Y-329485D01*
X369592Y-329435D01*
X368972D01*
G01X-247901Y-428634D02*
Y1008173D01*
X2091018D01*
Y-428634D01*
X-247901D01*
G01X-115095Y-307460D02*
X-115565Y-307145D01*
X-116113Y-306935D01*
X-116740D01*
X-117445Y-307250D01*
X-117993Y-307775D01*
X-118385Y-308405D01*
X-118698Y-309455D01*
X-118776Y-310400D01*
X-118620Y-311345D01*
X-118385Y-311975D01*
X-117915Y-312605D01*
X-117366Y-313025D01*
X-116818Y-313235D01*
X-116270D01*
X-115721Y-313025D01*
X-115251Y-312710D01*
X-114860Y-312290D01*
G01X-111458Y-306935D02*
X-109578D01*
G01X-110518D02*
Y-313235D01*
G01X-111458D02*
X-109578D01*
G01X-104218Y-306935D02*
Y-313235D01*
G01X-106020Y-306935D02*
X-102416D01*
G01X-97918Y-313235D02*
Y-310400D01*
X-99485Y-306935D01*
G01X-96351D02*
X-97918Y-310400D01*
G01X-87041Y-311975D02*
X-86571Y-312710D01*
X-85945Y-313130D01*
X-85240Y-313235D01*
X-84613Y-313130D01*
X-83986Y-312605D01*
X-83595Y-311975D01*
X-83516Y-311345D01*
X-83673Y-310610D01*
X-84221Y-310085D01*
X-84770Y-309875D01*
X-85475D01*
G01X-84770D02*
X-84300Y-309560D01*
X-83908Y-309035D01*
X-83751Y-308405D01*
X-83908Y-307775D01*
X-84300Y-307250D01*
X-85005Y-306935D01*
X-85710Y-307040D01*
X-86415Y-307460D01*
G01X-80741Y-311975D02*
X-80271Y-312710D01*
X-79645Y-313130D01*
X-78940Y-313235D01*
X-78313Y-313130D01*
X-77686Y-312605D01*
X-77295Y-311975D01*
X-77216Y-311345D01*
X-77373Y-310610D01*
X-77921Y-310085D01*
X-78470Y-309875D01*
X-79175D01*
G01X-78470D02*
X-78000Y-309560D01*
X-77608Y-309035D01*
X-77451Y-308405D01*
X-77608Y-307775D01*
X-78000Y-307250D01*
X-78705Y-306935D01*
X-79410Y-307040D01*
X-80115Y-307460D01*
G01X-74441Y-311975D02*
X-73971Y-312710D01*
X-73345Y-313130D01*
X-72640Y-313235D01*
X-72013Y-313130D01*
X-71386Y-312605D01*
X-70995Y-311975D01*
X-70916Y-311345D01*
X-71073Y-310610D01*
X-71621Y-310085D01*
X-72170Y-309875D01*
X-72875D01*
G01X-72170D02*
X-71700Y-309560D01*
X-71308Y-309035D01*
X-71151Y-308405D01*
X-71308Y-307775D01*
X-71700Y-307250D01*
X-72405Y-306935D01*
X-73110Y-307040D01*
X-73815Y-307460D01*
G01X-66575Y-313235D02*
X-66418Y-311870D01*
X-66183Y-310715D01*
X-65870Y-309665D01*
X-65478Y-308510D01*
X-64851Y-306935D01*
X-67985D01*
G01X-60275Y-313235D02*
X-60118Y-311870D01*
X-59883Y-310715D01*
X-59570Y-309665D01*
X-59178Y-308510D01*
X-58551Y-306935D01*
X-61685D01*
G01X-53975Y-314390D02*
X-53661Y-313025D01*
G01X-47518Y-306935D02*
Y-313235D01*
G01X-49320Y-306935D02*
X-45716D01*
G01X-43176Y-313235D02*
X-41218Y-306935D01*
X-39260Y-313235D01*
G01X-39965Y-311030D02*
X-42471D01*
G01X-35858Y-306935D02*
X-33978D01*
G01X-34918D02*
Y-313235D01*
G01X-35858D02*
X-33978D01*
G01X-30968Y-306935D02*
X-29871Y-313235D01*
X-28618Y-306935D01*
X-27365Y-313235D01*
X-26268Y-306935D01*
G01X-24276Y-313235D02*
X-22318Y-306935D01*
X-20360Y-313235D01*
G01X-21065Y-311030D02*
X-23571D01*
G01X-17820Y-313235D02*
Y-306935D01*
X-14216Y-313235D01*
Y-306935D01*
G01X-3810Y-315335D02*
X-4593Y-314285D01*
X-4985Y-313235D01*
Y-309035D01*
X-4593Y-307985D01*
X-3810Y-306935D01*
G01X7615Y-313235D02*
Y-306935D01*
X9574D01*
X10200Y-307250D01*
X10592Y-307670D01*
X10749Y-308510D01*
X10592Y-309350D01*
X10122Y-309875D01*
X9574Y-310190D01*
X7615D01*
G01X9574D02*
X10749Y-313235D01*
G01X15482Y-313445D02*
X15325Y-313340D01*
Y-313130D01*
X15482Y-313025D01*
X15639Y-313130D01*
Y-313340D01*
X15482Y-313445D01*
G01X21782Y-313235D02*
X21155Y-313130D01*
X20607Y-312710D01*
X20137Y-312080D01*
X19824Y-311345D01*
X19667Y-310505D01*
Y-309665D01*
X19824Y-308825D01*
X20137Y-308090D01*
X20607Y-307460D01*
X21155Y-307040D01*
X21782Y-306935D01*
X22409Y-307040D01*
X22957Y-307460D01*
X23427Y-308090D01*
X23740Y-308825D01*
X23897Y-309665D01*
Y-310505D01*
X23740Y-311345D01*
X23427Y-312080D01*
X22957Y-312710D01*
X22409Y-313130D01*
X21782Y-313235D01*
G01X28082Y-313445D02*
X27925Y-313340D01*
Y-313130D01*
X28082Y-313025D01*
X28239Y-313130D01*
Y-313340D01*
X28082Y-313445D01*
G01X36105Y-307460D02*
X35635Y-307145D01*
X35087Y-306935D01*
X34460D01*
X33755Y-307250D01*
X33207Y-307775D01*
X32815Y-308405D01*
X32502Y-309455D01*
X32424Y-310400D01*
X32580Y-311345D01*
X32815Y-311975D01*
X33285Y-312605D01*
X33834Y-313025D01*
X34382Y-313235D01*
X34930D01*
X35479Y-313025D01*
X35949Y-312710D01*
X36340Y-312290D01*
G01X40682Y-313445D02*
X40525Y-313340D01*
Y-313130D01*
X40682Y-313025D01*
X40839Y-313130D01*
Y-313340D01*
X40682Y-313445D01*
G01X47374Y-315335D02*
X48157Y-314285D01*
X48549Y-313235D01*
Y-309035D01*
X48157Y-307985D01*
X47374Y-306935D01*
G01X-118620Y-293235D02*
Y-286935D01*
X-115016Y-293235D01*
Y-286935D01*
G01X-110518Y-293235D02*
X-111145Y-293130D01*
X-111693Y-292710D01*
X-112163Y-292080D01*
X-112476Y-291345D01*
X-112633Y-290505D01*
Y-289665D01*
X-112476Y-288825D01*
X-112163Y-288090D01*
X-111693Y-287460D01*
X-111145Y-287040D01*
X-110518Y-286935D01*
X-109891Y-287040D01*
X-109343Y-287460D01*
X-108873Y-288090D01*
X-108560Y-288825D01*
X-108403Y-289665D01*
Y-290505D01*
X-108560Y-291345D01*
X-108873Y-292080D01*
X-109343Y-292710D01*
X-109891Y-293130D01*
X-110518Y-293235D01*
G01X-104218Y-293445D02*
X-104375Y-293340D01*
Y-293130D01*
X-104218Y-293025D01*
X-104061Y-293130D01*
Y-293340D01*
X-104218Y-293445D01*
G01X-99406Y-287985D02*
X-98936Y-287355D01*
X-98388Y-287040D01*
X-97761Y-286935D01*
X-96978Y-287145D01*
X-96430Y-287670D01*
X-96273Y-288300D01*
X-96351Y-288930D01*
X-96665Y-289455D01*
X-98231Y-290505D01*
X-98936Y-291240D01*
X-99406Y-292290D01*
X-99563Y-293235D01*
X-96273D01*
G01X-91618D02*
Y-286935D01*
X-92558Y-288195D01*
G01Y-293235D02*
X-90678D01*
G01X-85318D02*
Y-286935D01*
X-86258Y-288195D01*
G01Y-293235D02*
X-84378D01*
G01X-79175Y-294390D02*
X-78861Y-293025D01*
G01X-75068Y-286935D02*
X-73971Y-293235D01*
X-72718Y-286935D01*
X-71465Y-293235D01*
X-70368Y-286935D01*
G01X-64851Y-293235D02*
X-67985D01*
Y-286935D01*
X-64851D01*
G01X-66105Y-289980D02*
X-67985D01*
G01X-61920Y-293235D02*
Y-286935D01*
X-58316Y-293235D01*
Y-286935D01*
G01X-55463Y-293235D02*
Y-286935D01*
G01X-52173D02*
Y-293235D01*
G01Y-290085D02*
X-55463D01*
G01X-49241Y-286935D02*
Y-291450D01*
X-48928Y-292395D01*
X-48301Y-293025D01*
X-47518Y-293235D01*
X-46735Y-293025D01*
X-46108Y-292395D01*
X-45795Y-291450D01*
Y-286935D01*
G01X-43176Y-293235D02*
X-41218Y-286935D01*
X-39260Y-293235D01*
G01X-39965Y-291030D02*
X-42471D01*
G01X-30106Y-287985D02*
X-29636Y-287355D01*
X-29088Y-287040D01*
X-28461Y-286935D01*
X-27678Y-287145D01*
X-27130Y-287670D01*
X-26973Y-288300D01*
X-27051Y-288930D01*
X-27365Y-289455D01*
X-28931Y-290505D01*
X-29636Y-291240D01*
X-30106Y-292290D01*
X-30263Y-293235D01*
X-26973D01*
G01X-24120D02*
Y-286935D01*
X-20516Y-293235D01*
Y-286935D01*
G01X-17741Y-293235D02*
Y-286935D01*
X-16175D01*
X-15548Y-287250D01*
X-15078Y-287670D01*
X-14686Y-288300D01*
X-14373Y-289035D01*
X-14295Y-290085D01*
X-14373Y-291135D01*
X-14686Y-291870D01*
X-15078Y-292500D01*
X-15548Y-292920D01*
X-16175Y-293235D01*
X-17741D01*
G01X-4985D02*
Y-286935D01*
X-3026D01*
X-2400Y-287250D01*
X-2008Y-287670D01*
X-1851Y-288510D01*
X-2008Y-289350D01*
X-2478Y-289875D01*
X-3026Y-290190D01*
X-4985D01*
G01X-3026D02*
X-1851Y-293235D01*
G01X1159D02*
Y-286935D01*
X2725D01*
X3352Y-287250D01*
X3822Y-287670D01*
X4214Y-288300D01*
X4527Y-289035D01*
X4605Y-290085D01*
X4527Y-291135D01*
X4214Y-291870D01*
X3822Y-292500D01*
X3352Y-292920D01*
X2725Y-293235D01*
X1159D01*
G01X9182Y-293445D02*
X9025Y-293340D01*
Y-293130D01*
X9182Y-293025D01*
X9339Y-293130D01*
Y-293340D01*
X9182Y-293445D01*
G01X-116348Y-300085D02*
X-114781D01*
Y-301975D01*
X-115251Y-302605D01*
X-115800Y-303025D01*
X-116583Y-303235D01*
X-117366Y-303025D01*
X-117915Y-302605D01*
X-118385Y-301975D01*
X-118698Y-301240D01*
X-118855Y-300400D01*
Y-299665D01*
X-118698Y-299035D01*
X-118385Y-298300D01*
X-117915Y-297670D01*
X-117445Y-297250D01*
X-116818Y-296935D01*
X-116270D01*
X-115643Y-297145D01*
X-115173Y-297565D01*
G01X-112241Y-296935D02*
Y-301450D01*
X-111928Y-302395D01*
X-111301Y-303025D01*
X-110518Y-303235D01*
X-109735Y-303025D01*
X-109108Y-302395D01*
X-108795Y-301450D01*
Y-296935D01*
G01X-105158D02*
X-103278D01*
G01X-104218D02*
Y-303235D01*
G01X-105158D02*
X-103278D01*
G01X-99563Y-302395D02*
X-98936Y-302920D01*
X-98231Y-303235D01*
X-97605D01*
X-96978Y-302920D01*
X-96508Y-302395D01*
X-96273Y-301660D01*
X-96430Y-300925D01*
X-96821Y-300295D01*
X-97526Y-299875D01*
X-98466Y-299665D01*
X-99015Y-299245D01*
X-99250Y-298510D01*
X-99093Y-297775D01*
X-98701Y-297250D01*
X-98153Y-296935D01*
X-97605D01*
X-97056Y-297145D01*
X-96586Y-297670D01*
G01X-93263Y-303235D02*
Y-296935D01*
G01X-89973D02*
Y-303235D01*
G01Y-300085D02*
X-93263D01*
G01X-87276Y-303235D02*
X-85318Y-296935D01*
X-83360Y-303235D01*
G01X-84065Y-301030D02*
X-86571D01*
G01X-80820Y-303235D02*
Y-296935D01*
X-77216Y-303235D01*
Y-296935D01*
G01X-68141Y-303235D02*
Y-296935D01*
X-66575D01*
X-65948Y-297250D01*
X-65478Y-297670D01*
X-65086Y-298300D01*
X-64773Y-299035D01*
X-64695Y-300085D01*
X-64773Y-301135D01*
X-65086Y-301870D01*
X-65478Y-302500D01*
X-65948Y-302920D01*
X-66575Y-303235D01*
X-68141D01*
G01X-61058Y-296935D02*
X-59178D01*
G01X-60118D02*
Y-303235D01*
G01X-61058D02*
X-59178D01*
G01X-55463Y-302395D02*
X-54836Y-302920D01*
X-54131Y-303235D01*
X-53505D01*
X-52878Y-302920D01*
X-52408Y-302395D01*
X-52173Y-301660D01*
X-52330Y-300925D01*
X-52721Y-300295D01*
X-53426Y-299875D01*
X-54366Y-299665D01*
X-54915Y-299245D01*
X-55150Y-298510D01*
X-54993Y-297775D01*
X-54601Y-297250D01*
X-54053Y-296935D01*
X-53505D01*
X-52956Y-297145D01*
X-52486Y-297670D01*
G01X-47518Y-296935D02*
Y-303235D01*
G01X-49320Y-296935D02*
X-45716D01*
G01X-41218Y-303445D02*
X-41375Y-303340D01*
Y-303130D01*
X-41218Y-303025D01*
X-41061Y-303130D01*
Y-303340D01*
X-41218Y-303445D01*
G01X-35075Y-304390D02*
X-34761Y-303025D01*
G01X-28618Y-296935D02*
Y-303235D01*
G01X-30420Y-296935D02*
X-26816D01*
G01X-24276Y-303235D02*
X-22318Y-296935D01*
X-20360Y-303235D01*
G01X-21065Y-301030D02*
X-23571D01*
G01X-16018Y-303235D02*
X-16645Y-303130D01*
X-17193Y-302710D01*
X-17663Y-302080D01*
X-17976Y-301345D01*
X-18133Y-300505D01*
Y-299665D01*
X-17976Y-298825D01*
X-17663Y-298090D01*
X-17193Y-297460D01*
X-16645Y-297040D01*
X-16018Y-296935D01*
X-15391Y-297040D01*
X-14843Y-297460D01*
X-14373Y-298090D01*
X-14060Y-298825D01*
X-13903Y-299665D01*
Y-300505D01*
X-14060Y-301345D01*
X-14373Y-302080D01*
X-14843Y-302710D01*
X-15391Y-303130D01*
X-16018Y-303235D01*
G01X-9718D02*
Y-300400D01*
X-11285Y-296935D01*
G01X-8151D02*
X-9718Y-300400D01*
G01X-5141Y-296935D02*
Y-301450D01*
X-4828Y-302395D01*
X-4201Y-303025D01*
X-3418Y-303235D01*
X-2635Y-303025D01*
X-2008Y-302395D01*
X-1695Y-301450D01*
Y-296935D01*
G01X924Y-303235D02*
X2882Y-296935D01*
X4840Y-303235D01*
G01X4135Y-301030D02*
X1629D01*
G01X7380Y-303235D02*
Y-296935D01*
X10984Y-303235D01*
Y-296935D01*
G01X-94518Y-282535D02*
X-97038Y-282118D01*
X-99243Y-280452D01*
X-101133Y-277952D01*
X-102393Y-275035D01*
X-103023Y-271702D01*
Y-268368D01*
X-102393Y-265035D01*
X-101133Y-262118D01*
X-99243Y-259619D01*
X-97038Y-257952D01*
X-94518Y-257535D01*
X-91998Y-257952D01*
X-89793Y-259619D01*
X-87903Y-262118D01*
X-86643Y-265035D01*
X-86013Y-268368D01*
Y-271702D01*
X-86643Y-275035D01*
X-87903Y-277952D01*
X-89793Y-280452D01*
X-91998Y-282118D01*
X-94518Y-282535D01*
G01X-91998Y-275868D02*
X-88218Y-282535D01*
G01X-74673Y-265869D02*
Y-277535D01*
X-73413Y-280452D01*
X-71523Y-282118D01*
X-69318Y-282535D01*
X-67113Y-282118D01*
X-65223Y-280452D01*
X-63963Y-277535D01*
G01Y-282535D02*
Y-265869D01*
G01X-38448Y-282535D02*
Y-265869D01*
G01Y-268785D02*
X-39708Y-267119D01*
X-41598Y-266285D01*
X-43803Y-265869D01*
X-46008Y-266702D01*
X-47898Y-268368D01*
X-49158Y-270869D01*
X-49788Y-274202D01*
X-49158Y-277535D01*
X-47898Y-280036D01*
X-46008Y-281702D01*
X-43803Y-282535D01*
X-41598Y-282118D01*
X-39708Y-280869D01*
X-38448Y-279202D01*
G01X-24273Y-282535D02*
Y-265869D01*
G01Y-270035D02*
X-23013Y-267952D01*
X-21123Y-266285D01*
X-18603Y-265869D01*
X-16398Y-266285D01*
X-14508Y-267952D01*
X-13563Y-270869D01*
Y-282535D01*
G01X6282Y-257535D02*
Y-282535D01*
G01X1872Y-265869D02*
X10692D01*
G01X37152Y-282535D02*
Y-265869D01*
G01Y-268785D02*
X35892Y-267119D01*
X34002Y-266285D01*
X31797Y-265869D01*
X29592Y-266702D01*
X27702Y-268368D01*
X26442Y-270869D01*
X25812Y-274202D01*
X26442Y-277535D01*
X27702Y-280036D01*
X29592Y-281702D01*
X31797Y-282535D01*
X34002Y-282118D01*
X35892Y-280869D01*
X37152Y-279202D01*
G01X76832Y-262235D02*
Y-270235D01*
X80832D01*
G01X88632D02*
Y-264902D01*
G01Y-265835D02*
X88232Y-265302D01*
X87632Y-265035D01*
X86932Y-264902D01*
X86232Y-265168D01*
X85632Y-265702D01*
X85232Y-266502D01*
X85032Y-267568D01*
X85232Y-268635D01*
X85632Y-269435D01*
X86232Y-269968D01*
X86932Y-270235D01*
X87632Y-270102D01*
X88232Y-269702D01*
X88632Y-269169D01*
G01X92732Y-272635D02*
X93332Y-272902D01*
X94132Y-272635D01*
X94632Y-272102D01*
X95032Y-271435D01*
X95632Y-269302D01*
X96932Y-264902D01*
G01X93732D02*
X95632Y-269302D01*
G01X101332Y-266635D02*
X104532D01*
X104232Y-265702D01*
X103732Y-265168D01*
X103032Y-264902D01*
X102332Y-265035D01*
X101732Y-265435D01*
X101332Y-266368D01*
X101132Y-267169D01*
Y-267968D01*
X101332Y-268768D01*
X101832Y-269568D01*
X102432Y-270102D01*
X103132Y-270235D01*
X103832Y-269968D01*
X104532Y-269169D01*
G01X109432Y-270235D02*
Y-264902D01*
G01Y-265968D02*
X109932Y-265435D01*
X110432Y-265035D01*
X111132Y-264902D01*
X111632Y-265035D01*
X112232Y-265435D01*
G01X95532Y-320235D02*
Y-312235D01*
X100132Y-320235D01*
Y-312235D01*
G01X105832Y-314902D02*
Y-320235D01*
G01Y-312768D02*
X105632Y-312635D01*
Y-312368D01*
X105832Y-312235D01*
X106032Y-312368D01*
Y-312635D01*
X105832Y-312768D01*
G01X112132Y-320235D02*
Y-314902D01*
G01Y-316235D02*
X112532Y-315568D01*
X113132Y-315035D01*
X113932Y-314902D01*
X114632Y-315035D01*
X115232Y-315568D01*
X115532Y-316502D01*
Y-320235D01*
G01X123632D02*
Y-314902D01*
G01Y-315835D02*
X123232Y-315302D01*
X122632Y-315035D01*
X121932Y-314902D01*
X121232Y-315168D01*
X120632Y-315702D01*
X120232Y-316502D01*
X120032Y-317568D01*
X120232Y-318635D01*
X120632Y-319435D01*
X121232Y-319968D01*
X121932Y-320235D01*
X122632Y-320102D01*
X123232Y-319702D01*
X123632Y-319169D01*
G01X88332Y-295235D02*
Y-287235D01*
X90732D01*
X91532Y-287635D01*
X92132Y-288568D01*
X92332Y-289635D01*
X92132Y-290702D01*
X91632Y-291502D01*
X90732Y-291902D01*
X88332D01*
G01X95832Y-295235D02*
X98332Y-287235D01*
X100832Y-295235D01*
G01X99932Y-292435D02*
X96732D01*
G01X104232Y-294169D02*
X105032Y-294835D01*
X105932Y-295235D01*
X106732D01*
X107532Y-294835D01*
X108132Y-294169D01*
X108432Y-293235D01*
X108232Y-292302D01*
X107732Y-291502D01*
X106832Y-290968D01*
X105632Y-290702D01*
X104932Y-290168D01*
X104632Y-289235D01*
X104832Y-288302D01*
X105332Y-287635D01*
X106032Y-287235D01*
X106732D01*
X107432Y-287502D01*
X108032Y-288168D01*
G01X114332Y-287235D02*
Y-295235D01*
G01X112032Y-287235D02*
X116632D01*
G01X121032Y-292568D02*
X123632D01*
G01X130332Y-287235D02*
Y-295235D01*
G01X128032Y-287235D02*
X132632D01*
G01X138332Y-295235D02*
X137532Y-295102D01*
X136832Y-294568D01*
X136232Y-293768D01*
X135832Y-292835D01*
X135632Y-291768D01*
Y-290702D01*
X135832Y-289635D01*
X136232Y-288702D01*
X136832Y-287902D01*
X137532Y-287368D01*
X138332Y-287235D01*
X139132Y-287368D01*
X139832Y-287902D01*
X140432Y-288702D01*
X140832Y-289635D01*
X141032Y-290702D01*
Y-291768D01*
X140832Y-292835D01*
X140432Y-293768D01*
X139832Y-294568D01*
X139132Y-295102D01*
X138332Y-295235D01*
G01X144332D02*
Y-287235D01*
X146732D01*
X147532Y-287635D01*
X148132Y-288568D01*
X148332Y-289635D01*
X148132Y-290702D01*
X147632Y-291502D01*
X146732Y-291902D01*
X144332D01*
G01X203432Y-313568D02*
X204032Y-312768D01*
X204732Y-312368D01*
X205532Y-312235D01*
X206532Y-312502D01*
X207232Y-313168D01*
X207432Y-313968D01*
X207332Y-314769D01*
X206932Y-315435D01*
X204932Y-316768D01*
X204032Y-317702D01*
X203432Y-319035D01*
X203232Y-320235D01*
X207432D01*
G01X213332Y-312235D02*
X212532Y-312502D01*
X211932Y-313168D01*
X211532Y-313968D01*
X211232Y-315035D01*
X211132Y-316235D01*
X211232Y-317435D01*
X211532Y-318502D01*
X211932Y-319302D01*
X212532Y-319968D01*
X213332Y-320235D01*
X214132Y-319968D01*
X214732Y-319302D01*
X215132Y-318502D01*
X215432Y-317435D01*
X215532Y-316235D01*
X215432Y-315035D01*
X215132Y-313968D01*
X214732Y-313168D01*
X214132Y-312502D01*
X213332Y-312235D01*
G01X219432Y-313568D02*
X220032Y-312768D01*
X220732Y-312368D01*
X221532Y-312235D01*
X222532Y-312502D01*
X223232Y-313168D01*
X223432Y-313968D01*
X223332Y-314769D01*
X222932Y-315435D01*
X220932Y-316768D01*
X220032Y-317702D01*
X219432Y-319035D01*
X219232Y-320235D01*
X223432D01*
G01X227432Y-313568D02*
X228032Y-312768D01*
X228732Y-312368D01*
X229532Y-312235D01*
X230532Y-312502D01*
X231232Y-313168D01*
X231432Y-313968D01*
X231332Y-314769D01*
X230932Y-315435D01*
X228932Y-316768D01*
X228032Y-317702D01*
X227432Y-319035D01*
X227232Y-320235D01*
X231432D01*
G01X235532Y-320502D02*
X239132Y-312235D01*
G01X245332Y-320235D02*
Y-312235D01*
X244132Y-313835D01*
G01Y-320235D02*
X246532D01*
G01X251432Y-313568D02*
X252032Y-312768D01*
X252732Y-312368D01*
X253532Y-312235D01*
X254532Y-312502D01*
X255232Y-313168D01*
X255432Y-313968D01*
X255332Y-314769D01*
X254932Y-315435D01*
X252932Y-316768D01*
X252032Y-317702D01*
X251432Y-319035D01*
X251232Y-320235D01*
X255432D01*
G01X259532Y-320502D02*
X263132Y-312235D01*
G01X269332D02*
X268532Y-312502D01*
X267932Y-313168D01*
X267532Y-313968D01*
X267232Y-315035D01*
X267132Y-316235D01*
X267232Y-317435D01*
X267532Y-318502D01*
X267932Y-319302D01*
X268532Y-319968D01*
X269332Y-320235D01*
X270132Y-319968D01*
X270732Y-319302D01*
X271132Y-318502D01*
X271432Y-317435D01*
X271532Y-316235D01*
X271432Y-315035D01*
X271132Y-313968D01*
X270732Y-313168D01*
X270132Y-312502D01*
X269332Y-312235D01*
G01X275632Y-319302D02*
X276332Y-319968D01*
X277132Y-320235D01*
X277932Y-319968D01*
X278632Y-319169D01*
X279132Y-317968D01*
X279332Y-316768D01*
Y-315302D01*
X279132Y-314102D01*
X278632Y-313035D01*
X278032Y-312502D01*
X277332Y-312235D01*
X276532Y-312502D01*
X275932Y-313035D01*
X275532Y-313835D01*
X275332Y-314902D01*
X275532Y-315835D01*
X276032Y-316768D01*
X276632Y-317302D01*
X277332Y-317435D01*
X278132Y-317169D01*
X278732Y-316502D01*
X279332Y-315302D01*
G01X205632Y-295235D02*
Y-287235D01*
X207632D01*
X208432Y-287635D01*
X209032Y-288168D01*
X209532Y-288968D01*
X209932Y-289902D01*
X210032Y-291235D01*
X209932Y-292568D01*
X209532Y-293502D01*
X209032Y-294302D01*
X208432Y-294835D01*
X207632Y-295235D01*
X205632D01*
G01X213332D02*
X215832Y-287235D01*
X218332Y-295235D01*
G01X217432Y-292435D02*
X214232D01*
G01X223832Y-287235D02*
X223032Y-287502D01*
X222432Y-288168D01*
X222032Y-288968D01*
X221732Y-290035D01*
X221632Y-291235D01*
X221732Y-292435D01*
X222032Y-293502D01*
X222432Y-294302D01*
X223032Y-294968D01*
X223832Y-295235D01*
X224632Y-294968D01*
X225232Y-294302D01*
X225632Y-293502D01*
X225932Y-292435D01*
X226032Y-291235D01*
X225932Y-290035D01*
X225632Y-288968D01*
X225232Y-288168D01*
X224632Y-287502D01*
X223832Y-287235D01*
G01X229932Y-295235D02*
Y-287235D01*
X233732D01*
G01X232332Y-291102D02*
X229932D01*
G01X239832Y-287235D02*
X239032Y-287502D01*
X238432Y-288168D01*
X238032Y-288968D01*
X237732Y-290035D01*
X237632Y-291235D01*
X237732Y-292435D01*
X238032Y-293502D01*
X238432Y-294302D01*
X239032Y-294968D01*
X239832Y-295235D01*
X240632Y-294968D01*
X241232Y-294302D01*
X241632Y-293502D01*
X241932Y-292435D01*
X242032Y-291235D01*
X241932Y-290035D01*
X241632Y-288968D01*
X241232Y-288168D01*
X240632Y-287502D01*
X239832Y-287235D01*
G01X247832D02*
Y-295235D01*
G01X245532Y-287235D02*
X250132D01*
G01X255832Y-295235D02*
Y-291635D01*
X253832Y-287235D01*
G01X257832D02*
X255832Y-291635D01*
G01X264632Y-290968D02*
X265032Y-290568D01*
X265332Y-289902D01*
X265532Y-288968D01*
X265332Y-288168D01*
X264932Y-287635D01*
X264232Y-287235D01*
X261532D01*
Y-295235D01*
X264832D01*
X265532Y-294702D01*
X265932Y-293902D01*
X266132Y-292968D01*
X265932Y-292035D01*
X265332Y-291235D01*
X264632Y-290968D01*
X261532D01*
G01X273032Y-295235D02*
Y-287235D01*
X269332Y-292968D01*
X274332D01*
G01X277632Y-295235D02*
Y-287235D01*
X279632D01*
X280432Y-287635D01*
X281032Y-288168D01*
X281532Y-288968D01*
X281932Y-289902D01*
X282032Y-291235D01*
X281932Y-292568D01*
X281532Y-293502D01*
X281032Y-294302D01*
X280432Y-294835D01*
X279632Y-295235D01*
X277632D01*
G01X287832Y-287235D02*
X287032Y-287502D01*
X286432Y-288168D01*
X286032Y-288968D01*
X285732Y-290035D01*
X285632Y-291235D01*
X285732Y-292435D01*
X286032Y-293502D01*
X286432Y-294302D01*
X287032Y-294968D01*
X287832Y-295235D01*
X288632Y-294968D01*
X289232Y-294302D01*
X289632Y-293502D01*
X289932Y-292435D01*
X290032Y-291235D01*
X289932Y-290035D01*
X289632Y-288968D01*
X289232Y-288168D01*
X288632Y-287502D01*
X287832Y-287235D01*
G01X233432Y-270235D02*
Y-262235D01*
X237232D01*
G01X235832Y-266102D02*
X233432D01*
G01X243332Y-262235D02*
X242532Y-262502D01*
X241932Y-263168D01*
X241532Y-263968D01*
X241232Y-265035D01*
X241132Y-266235D01*
X241232Y-267435D01*
X241532Y-268502D01*
X241932Y-269302D01*
X242532Y-269968D01*
X243332Y-270235D01*
X244132Y-269968D01*
X244732Y-269302D01*
X245132Y-268502D01*
X245432Y-267435D01*
X245532Y-266235D01*
X245432Y-265035D01*
X245132Y-263968D01*
X244732Y-263168D01*
X244132Y-262502D01*
X243332Y-262235D01*
G01X251332D02*
Y-270235D01*
G01X249032Y-262235D02*
X253632D01*
G01X256332Y-272902D02*
X262332D01*
G01X265332Y-270235D02*
Y-262235D01*
X267732D01*
X268532Y-262635D01*
X269132Y-263568D01*
X269332Y-264635D01*
X269132Y-265702D01*
X268632Y-266502D01*
X267732Y-266902D01*
X265332D01*
G01X272832Y-270235D02*
X275332Y-262235D01*
X277832Y-270235D01*
G01X276932Y-267435D02*
X273732D01*
G01X281032Y-270235D02*
Y-262235D01*
X285632Y-270235D01*
Y-262235D01*
G01X293332Y-270235D02*
X289332D01*
Y-262235D01*
X293332D01*
G01X291732Y-266102D02*
X289332D01*
G01X297332Y-262235D02*
Y-270235D01*
X301332D01*
G01X304332Y-272902D02*
X310332D01*
G01X316132Y-265968D02*
X316532Y-265568D01*
X316832Y-264902D01*
X317032Y-263968D01*
X316832Y-263168D01*
X316432Y-262635D01*
X315732Y-262235D01*
X313032D01*
Y-270235D01*
X316332D01*
X317032Y-269702D01*
X317432Y-268902D01*
X317632Y-267968D01*
X317432Y-267035D01*
X316832Y-266235D01*
X316132Y-265968D01*
X313032D01*
G01X321132Y-270235D02*
Y-262235D01*
X323132D01*
X323932Y-262635D01*
X324532Y-263168D01*
X325032Y-263968D01*
X325432Y-264902D01*
X325532Y-266235D01*
X325432Y-267568D01*
X325032Y-268502D01*
X324532Y-269302D01*
X323932Y-269835D01*
X323132Y-270235D01*
X321132D01*
G01X291832Y-323235D02*
Y-315235D01*
X290632Y-316835D01*
G01Y-323235D02*
X293032D01*
G01X297932Y-319902D02*
X298632Y-318968D01*
X299232Y-318435D01*
X300032Y-318168D01*
X300732Y-318435D01*
X301232Y-318968D01*
X301632Y-319768D01*
X301732Y-320702D01*
X301632Y-321502D01*
X301232Y-322302D01*
X300632Y-322968D01*
X299932Y-323235D01*
X299132Y-322968D01*
X298432Y-322169D01*
X298032Y-320968D01*
X297932Y-319635D01*
X298132Y-317902D01*
X298432Y-316968D01*
X298932Y-316035D01*
X299632Y-315368D01*
X300332Y-315235D01*
X301032Y-315502D01*
X301532Y-316168D01*
G01X307832Y-323502D02*
X307632Y-323368D01*
Y-323102D01*
X307832Y-322968D01*
X308032Y-323102D01*
Y-323368D01*
X307832Y-323502D01*
G01X313932Y-319902D02*
X314632Y-318968D01*
X315232Y-318435D01*
X316032Y-318168D01*
X316732Y-318435D01*
X317232Y-318968D01*
X317632Y-319768D01*
X317732Y-320702D01*
X317632Y-321502D01*
X317232Y-322302D01*
X316632Y-322968D01*
X315932Y-323235D01*
X315132Y-322968D01*
X314432Y-322169D01*
X314032Y-320968D01*
X313932Y-319635D01*
X314132Y-317902D01*
X314432Y-316968D01*
X314932Y-316035D01*
X315632Y-315368D01*
X316332Y-315235D01*
X317032Y-315502D01*
X317532Y-316168D01*
G01X336832Y-323235D02*
Y-315235D01*
X335632Y-316835D01*
G01Y-323235D02*
X338032D01*
G01X344632D02*
X344832Y-321502D01*
X345132Y-320035D01*
X345532Y-318702D01*
X346032Y-317235D01*
X346832Y-315235D01*
X342832D01*
G01X352832Y-323502D02*
X352632Y-323368D01*
Y-323102D01*
X352832Y-322968D01*
X353032Y-323102D01*
Y-323368D01*
X352832Y-323502D01*
G01X358932Y-316568D02*
X359532Y-315768D01*
X360232Y-315368D01*
X361032Y-315235D01*
X362032Y-315502D01*
X362732Y-316168D01*
X362932Y-316968D01*
X362832Y-317769D01*
X362432Y-318435D01*
X360432Y-319768D01*
X359532Y-320702D01*
X358932Y-322035D01*
X358732Y-323235D01*
X362932D01*
G01X356632Y-298235D02*
Y-290235D01*
X358632D01*
X359432Y-290635D01*
X360032Y-291168D01*
X360532Y-291968D01*
X360932Y-292902D01*
X361032Y-294235D01*
X360932Y-295568D01*
X360532Y-296502D01*
X360032Y-297302D01*
X359432Y-297835D01*
X358632Y-298235D01*
X356632D01*
G54D29*
X59500Y57516D03*
X65000Y76016D03*
X59500Y97516D03*
X81500Y248016D03*
X85500D03*
G54D38*
X87756Y89370D03*
X109095Y47244D03*
G54D39*
X94882Y82008D03*
M02*
